# SCM (Grand Teton) — schematic netlist excerpt (pin names and nets, part order shuffled) for the footprints in the layout excerpt that follows; sources: Cadence DE-HDL packaged netlist, KiCad conversion of 12092022_DA0F0TMDCD0_F0T_Management_Board_D_brd_V3_OCP.brd

R345  Q_RES  120 1% CHIP  pkg 0402LF  page 20 : A = GND ; B = M_BMC_DDR4_MBG0
R35  Q_RES  0 5% CHIP  pkg 0402LF  page 53 : A = PWRGD_P2V5_AUX ; B = PWRGD_P2V5_AUX_R

(kicad_pcb
	(version 20260206)
	(generator "pcbnew")
	(generator_version "10.0")
	(general
		(thickness 1.6)
		(legacy_teardrops no)
	)
	(paper "A4")
	(title_block
		(title "12092022_DA0F0TMDCD0_F0T_Management_Board_D_brd_V3_OCP.brd")
		(comment 1 "Grand Teton / footprints 745-746 of 1440")
	)
	(layers
		(0 "F.Cu" signal "TOP")
		(4 "In1.Cu" signal "GND")
		(6 "In2.Cu" signal "IN1")
		(8 "In3.Cu" signal "GND1")
		(10 "In4.Cu" signal "IN2")
		(12 "In5.Cu" signal "VCC")
		(14 "In6.Cu" signal "VCC1")
		(16 "In7.Cu" signal "IN3")
		(18 "In8.Cu" signal "GND2")
		(20 "In9.Cu" signal "IN4")
		(22 "In10.Cu" signal "GND3")
		(2 "B.Cu" signal "BOTTOM")
		(9 "F.Adhes" user "F.Adhesive")
		(11 "B.Adhes" user "B.Adhesive")
		(13 "F.Paste" user "Package Geometry/Pastemask Top")
		(15 "B.Paste" user "Package Geometry/Pastemask Bottom")
		(5 "F.SilkS" user "Ref Des/Silkscreen Top")
		(7 "B.SilkS" user "Ref Des/Silkscreen Bottom")
		(1 "F.Mask" user "Board Geometry/Soldermask Top")
		(3 "B.Mask" user "Board Geometry/Soldermask Bottom")
		(17 "Dwgs.User" user "User.Drawings")
		(19 "Cmts.User" user "User.Comments")
		(21 "Eco1.User" user "User.Eco1")
		(23 "Eco2.User" user "User.Eco2")
		(25 "Edge.Cuts" user "Board Geometry/Outline")
		(27 "Margin" user)
		(31 "F.CrtYd" user "Package Geometry/Place Bound Top")
		(29 "B.CrtYd" user "Package Geometry/Place Bound Bottom")
		(35 "F.Fab" user "Ref Des/Assembly Top")
		(33 "B.Fab" user "Ref Des/Assembly Bottom")
	)
	(footprint ""
		(layer "B.Cu")
		(at 79.756 -33.4645 -90)
		(property "Reference" "R35"
			(at 0 0 90)
			(layer "B.SilkS")
			(hide yes)
			(effects
				(font
					(size 1.27 1.27)
				)
				(justify mirror)
			)
		)
		(property "Value" ""
			(at 0 0 90)
			(layer "B.Fab")
			(effects
				(font
					(size 1.27 1.27)
				)
				(justify mirror)
			)
		)
		(duplicate_pad_numbers_are_jumpers no)
		(fp_line
			(start -0.7874 0.4064)
			(end 0.7874 0.4064)
			(stroke
				(width 0.1524)
				(type default)
			)
			(layer "B.SilkS")
		)
		(fp_line
			(start 0.7874 0.4064)
			(end 0.7874 -0.4064)
			(stroke
				(width 0.1524)
				(type default)
			)
			(layer "B.SilkS")
		)
		(fp_line
			(start -0.7874 -0.4064)
			(end -0.7874 0.4064)
			(stroke
				(width 0.1524)
				(type default)
			)
			(layer "B.SilkS")
		)
		(fp_line
			(start 0.7874 -0.4064)
			(end -0.7874 -0.4064)
			(stroke
				(width 0.1524)
				(type default)
			)
			(layer "B.SilkS")
		)
		(fp_line
			(start -0.67945 0.3048)
			(end -0.120396 0.3048)
			(stroke
				(width 0.1)
				(type default)
			)
			(layer "B.Fab")
		)
		(fp_line
			(start -0.120396 0.3048)
			(end -0.120396 0.2794)
			(stroke
				(width 0.1)
				(type default)
			)
			(layer "B.Fab")
		)
		(fp_line
			(start 0.12065 0.3048)
			(end 0.67945 0.3048)
			(stroke
				(width 0.1)
				(type default)
			)
			(layer "B.Fab")
		)
		(fp_line
			(start 0.67945 0.3048)
			(end 0.67945 -0.305054)
			(stroke
				(width 0.1)
				(type default)
			)
			(layer "B.Fab")
		)
		(fp_line
			(start -0.120396 0.2794)
			(end 0.12065 0.2794)
			(stroke
				(width 0.1)
				(type default)
			)
			(layer "B.Fab")
		)
		(fp_line
			(start 0.12065 0.2794)
			(end 0.12065 0.3048)
			(stroke
				(width 0.1)
				(type default)
			)
			(layer "B.Fab")
		)
		(fp_line
			(start -0.12065 -0.2794)
			(end -0.12065 -0.3048)
			(stroke
				(width 0.1)
				(type default)
			)
			(layer "B.Fab")
		)
		(fp_line
			(start 0.12065 -0.2794)
			(end -0.12065 -0.2794)
			(stroke
				(width 0.1)
				(type default)
			)
			(layer "B.Fab")
		)
		(fp_line
			(start -0.67945 -0.3048)
			(end -0.67945 0.3048)
			(stroke
				(width 0.1)
				(type default)
			)
			(layer "B.Fab")
		)
		(fp_line
			(start -0.12065 -0.3048)
			(end -0.67945 -0.3048)
			(stroke
				(width 0.1)
				(type default)
			)
			(layer "B.Fab")
		)
		(fp_line
			(start 0.12065 -0.305054)
			(end 0.12065 -0.2794)
			(stroke
				(width 0.1)
				(type default)
			)
			(layer "B.Fab")
		)
		(fp_line
			(start 0.67945 -0.305054)
			(end 0.12065 -0.305054)
			(stroke
				(width 0.1)
				(type default)
			)
			(layer "B.Fab")
		)
		(pad "1" smd circle
			(at 0.40005 0 90)
			(size 0 0)
			(layers "B.Cu" "B.Mask" "B.Paste")
			(net "PWRGD_P2V5_AUX")
		)
		(pad "2" smd circle
			(at -0.40005 0 90)
			(size 0 0)
			(layers "B.Cu" "B.Mask" "B.Paste")
			(net "PWRGD_P2V5_AUX_R")
		)
	)
	(footprint ""
		(layer "B.Cu")
		(at 81.129886 -39.974012)
		(property "Reference" "R345"
			(at 0 0 0)
			(layer "B.SilkS")
			(hide yes)
			(effects
				(font
					(size 1.27 1.27)
				)
				(justify mirror)
			)
		)
		(property "Value" ""
			(at 0 0 0)
			(layer "B.Fab")
			(effects
				(font
					(size 1.27 1.27)
				)
				(justify mirror)
			)
		)
		(duplicate_pad_numbers_are_jumpers no)
		(fp_line
			(start -0.7874 -0.4064)
			(end -0.7874 0.4064)
			(stroke
				(width 0.1524)
				(type default)
			)
			(layer "B.SilkS")
		)
		(fp_line
			(start -0.7874 0.4064)
			(end 0.7874 0.4064)
			(stroke
				(width 0.1524)
				(type default)
			)
			(layer "B.SilkS")
		)
		(fp_line
			(start 0.7874 -0.4064)
			(end -0.7874 -0.4064)
			(stroke
				(width 0.1524)
				(type default)
			)
			(layer "B.SilkS")
		)
		(fp_line
			(start 0.7874 0.4064)
			(end 0.7874 -0.4064)
			(stroke
				(width 0.1524)
				(type default)
			)
			(layer "B.SilkS")
		)
		(fp_line
			(start -0.67945 -0.3048)
			(end -0.67945 0.3048)
			(stroke
				(width 0.1)
				(type default)
			)
			(layer "B.Fab")
		)
		(fp_line
			(start -0.67945 0.3048)
			(end -0.120396 0.3048)
			(stroke
				(width 0.1)
				(type default)
			)
			(layer "B.Fab")
		)
		(fp_line
			(start -0.12065 -0.3048)
			(end -0.67945 -0.3048)
			(stroke
				(width 0.1)
				(type default)
			)
			(layer "B.Fab")
		)
		(fp_line
			(start -0.12065 -0.2794)
			(end -0.12065 -0.3048)
			(stroke
				(width 0.1)
				(type default)
			)
			(layer "B.Fab")
		)
		(fp_line
			(start -0.120396 0.2794)
			(end 0.12065 0.2794)
			(stroke
				(width 0.1)
				(type default)
			)
			(layer "B.Fab")
		)
		(fp_line
			(start -0.120396 0.3048)
			(end -0.120396 0.2794)
			(stroke
				(width 0.1)
				(type default)
			)
			(layer "B.Fab")
		)
		(fp_line
			(start 0.12065 -0.305054)
			(end 0.12065 -0.2794)
			(stroke
				(width 0.1)
				(type default)
			)
			(layer "B.Fab")
		)
		(fp_line
			(start 0.12065 -0.2794)
			(end -0.12065 -0.2794)
			(stroke
				(width 0.1)
				(type default)
			)
			(layer "B.Fab")
		)
		(fp_line
			(start 0.12065 0.2794)
			(end 0.12065 0.3048)
			(stroke
				(width 0.1)
				(type default)
			)
			(layer "B.Fab")
		)
		(fp_line
			(start 0.12065 0.3048)
			(end 0.67945 0.3048)
			(stroke
				(width 0.1)
				(type default)
			)
			(layer "B.Fab")
		)
		(fp_line
			(start 0.67945 -0.305054)
			(end 0.12065 -0.305054)
			(stroke
				(width 0.1)
				(type default)
			)
			(layer "B.Fab")
		)
		(fp_line
			(start 0.67945 0.3048)
			(end 0.67945 -0.305054)
			(stroke
				(width 0.1)
				(type default)
			)
			(layer "B.Fab")
		)
		(pad "1" smd circle
			(at 0.40005 0 180)
			(size 0 0)
			(layers "B.Cu" "B.Mask" "B.Paste")
			(net "GND")
		)
		(pad "2" smd circle
			(at -0.40005 0 180)
			(size 0 0)
			(layers "B.Cu" "B.Mask" "B.Paste")
			(net "M_BMC_DDR4_MBG0")
		)
	)
)
